FILE_TYPE=LIBRARY_PARTS;
TIME=' Compilation on Wed Jan 31 17:00:00 2001';
PRIMITIVE 'CAPP','CAPP_TH';
PIN
 'A':
   PIN_NUMBER='(1)';
   PIN_TYPE='UNSPEC';
   NO_LOAD_CHECK='BOTH';
   NO_IO_CHECK='BOTH';
   ALLOW_CONNECT='TRUE';
 'B':
   PIN_NUMBER='(2)';
   PIN_TYPE='UNSPEC';
   NO_LOAD_CHECK='BOTH';
   NO_IO_CHECK='BOTH';
   ALLOW_CONNECT='TRUE';
END_PIN;
BODY
 PART_NAME='CAPP';
 PHYS_DES_PREFIX='C';
END_BODY;
END_PRIMITIVE;
END.

